# T6G (Grand Teton) — schematic netlist excerpt (pin names and nets, part order shuffled) for the footprints in the layout excerpt that follows; sources: Cadence DE-HDL packaged netlist, KiCad conversion of 04192023_DAF0TMB3IC0_F0TG_MB_C_brd_V02_OCP.brd

R744  Q_RES  0 5% CHIP  pkg 0402LF  page 167 : A = PRSNT_CPU1_N ; B = FM_PRSNT_CPU1_N
C6063  Q_CAP  0.01UF 50V 10% X7R  pkg C0402  page 177 : A = P1V2_AUX ; B = GND

(kicad_pcb
	(version 20260206)
	(generator "pcbnew")
	(generator_version "10.0")
	(general
		(thickness 1.6)
		(legacy_teardrops no)
	)
	(paper "A4")
	(title_block
		(title "04192023_DAF0TMB3IC0_F0TG_MB_C_brd_V02_OCP.brd")
		(comment 1 "Grand Teton / footprints 8353-8354 of 8354")
	)
	(layers
		(0 "F.Cu" signal "TOP")
		(4 "In1.Cu" signal "GND")
		(6 "In2.Cu" signal "IN1")
		(8 "In3.Cu" signal "GND1")
		(10 "In4.Cu" signal "IN2")
		(12 "In5.Cu" signal "GND2")
		(14 "In6.Cu" signal "IN3")
		(16 "In7.Cu" signal "GND3")
		(18 "In8.Cu" signal "VCC")
		(20 "In9.Cu" signal "VCC1")
		(22 "In10.Cu" signal "GND4")
		(24 "In11.Cu" signal "IN4")
		(26 "In12.Cu" signal "GND5")
		(28 "In13.Cu" signal "IN5")
		(30 "In14.Cu" signal "GND6")
		(32 "In15.Cu" signal "IN6")
		(34 "In16.Cu" signal "GND7")
		(2 "B.Cu" signal "BOTTOM")
		(9 "F.Adhes" user "F.Adhesive")
		(11 "B.Adhes" user "B.Adhesive")
		(13 "F.Paste" user "Package Geometry/Pastemask Top")
		(15 "B.Paste" user "Package Geometry/Pastemask Bottom")
		(5 "F.SilkS" user "Ref Des/Silkscreen Top")
		(7 "B.SilkS" user "Ref Des/Silkscreen Bottom")
		(1 "F.Mask" user "Board Geometry/Soldermask Top")
		(3 "B.Mask" user "Board Geometry/Soldermask Bottom")
		(17 "Dwgs.User" user "User.Drawings")
		(19 "Cmts.User" user "User.Comments")
		(21 "Eco1.User" user "User.Eco1")
		(23 "Eco2.User" user "User.Eco2")
		(25 "Edge.Cuts" user "Board Geometry/Outline")
		(27 "Margin" user)
		(31 "F.CrtYd" user "Package Geometry/Place Bound Top")
		(29 "B.CrtYd" user "Package Geometry/Place Bound Bottom")
		(35 "F.Fab" user "Ref Des/Assembly Top")
		(33 "B.Fab" user "Ref Des/Assembly Bottom")
	)
	(footprint ""
		(layer "B.Cu")
		(at 129.20218 -37.09543 -90)
		(property "Reference" "C6063"
			(at 0 0 90)
			(layer "B.SilkS")
			(hide yes)
			(effects
				(font
					(size 1.27 1.27)
				)
				(justify mirror)
			)
		)
		(property "Value" ""
			(at 0 0 90)
			(layer "B.Fab")
			(effects
				(font
					(size 1.27 1.27)
				)
				(justify mirror)
			)
		)
		(duplicate_pad_numbers_are_jumpers no)
		(fp_line
			(start -0.7874 0.4064)
			(end 0.7874 0.4064)
			(stroke
				(width 0.1524)
				(type default)
			)
			(layer "B.SilkS")
		)
		(fp_line
			(start 0.7874 0.4064)
			(end 0.7874 -0.4064)
			(stroke
				(width 0.1524)
				(type default)
			)
			(layer "B.SilkS")
		)
		(fp_line
			(start -0.7874 -0.4064)
			(end -0.7874 0.4064)
			(stroke
				(width 0.1524)
				(type default)
			)
			(layer "B.SilkS")
		)
		(fp_line
			(start 0.7874 -0.4064)
			(end -0.7874 -0.4064)
			(stroke
				(width 0.1524)
				(type default)
			)
			(layer "B.SilkS")
		)
		(fp_line
			(start -0.67945 0.3048)
			(end -0.120396 0.3048)
			(stroke
				(width 0.1)
				(type default)
			)
			(layer "B.Fab")
		)
		(fp_line
			(start -0.120396 0.3048)
			(end -0.120396 0.2794)
			(stroke
				(width 0.1)
				(type default)
			)
			(layer "B.Fab")
		)
		(fp_line
			(start 0.12065 0.3048)
			(end 0.67945 0.3048)
			(stroke
				(width 0.1)
				(type default)
			)
			(layer "B.Fab")
		)
		(fp_line
			(start 0.67945 0.3048)
			(end 0.67945 -0.305054)
			(stroke
				(width 0.1)
				(type default)
			)
			(layer "B.Fab")
		)
		(fp_line
			(start -0.120396 0.2794)
			(end 0.12065 0.2794)
			(stroke
				(width 0.1)
				(type default)
			)
			(layer "B.Fab")
		)
		(fp_line
			(start 0.12065 0.2794)
			(end 0.12065 0.3048)
			(stroke
				(width 0.1)
				(type default)
			)
			(layer "B.Fab")
		)
		(fp_line
			(start -0.12065 -0.2794)
			(end -0.12065 -0.3048)
			(stroke
				(width 0.1)
				(type default)
			)
			(layer "B.Fab")
		)
		(fp_line
			(start 0.12065 -0.2794)
			(end -0.12065 -0.2794)
			(stroke
				(width 0.1)
				(type default)
			)
			(layer "B.Fab")
		)
		(fp_line
			(start -0.67945 -0.3048)
			(end -0.67945 0.3048)
			(stroke
				(width 0.1)
				(type default)
			)
			(layer "B.Fab")
		)
		(fp_line
			(start -0.12065 -0.3048)
			(end -0.67945 -0.3048)
			(stroke
				(width 0.1)
				(type default)
			)
			(layer "B.Fab")
		)
		(fp_line
			(start 0.12065 -0.305054)
			(end 0.12065 -0.2794)
			(stroke
				(width 0.1)
				(type default)
			)
			(layer "B.Fab")
		)
		(fp_line
			(start 0.67945 -0.305054)
			(end 0.12065 -0.305054)
			(stroke
				(width 0.1)
				(type default)
			)
			(layer "B.Fab")
		)
		(pad "1" smd circle
			(at 0.40005 0 90)
			(size 0 0)
			(layers "B.Cu" "B.Mask" "B.Paste")
			(net "P1V2_AUX")
		)
		(pad "2" smd circle
			(at -0.40005 0 90)
			(size 0 0)
			(layers "B.Cu" "B.Mask" "B.Paste")
			(net "GND")
		)
	)
	(footprint ""
		(layer "B.Cu")
		(at 426.53585 -33.467548 180)
		(property "Reference" "R744"
			(at 0 0 0)
			(layer "B.SilkS")
			(hide yes)
			(effects
				(font
					(size 1.27 1.27)
				)
				(justify mirror)
			)
		)
		(property "Value" ""
			(at 0 0 0)
			(layer "B.Fab")
			(effects
				(font
					(size 1.27 1.27)
				)
				(justify mirror)
			)
		)
		(duplicate_pad_numbers_are_jumpers no)
		(fp_line
			(start 0.7874 0.4064)
			(end 0.7874 -0.4064)
			(stroke
				(width 0.1524)
				(type default)
			)
			(layer "B.SilkS")
		)
		(fp_line
			(start 0.7874 -0.4064)
			(end -0.7874 -0.4064)
			(stroke
				(width 0.1524)
				(type default)
			)
			(layer "B.SilkS")
		)
		(fp_line
			(start -0.7874 0.4064)
			(end 0.7874 0.4064)
			(stroke
				(width 0.1524)
				(type default)
			)
			(layer "B.SilkS")
		)
		(fp_line
			(start -0.7874 -0.4064)
			(end -0.7874 0.4064)
			(stroke
				(width 0.1524)
				(type default)
			)
			(layer "B.SilkS")
		)
		(fp_line
			(start 0.67945 0.3048)
			(end 0.67945 -0.305054)
			(stroke
				(width 0.1)
				(type default)
			)
			(layer "B.Fab")
		)
		(fp_line
			(start 0.67945 -0.305054)
			(end 0.12065 -0.305054)
			(stroke
				(width 0.1)
				(type default)
			)
			(layer "B.Fab")
		)
		(fp_line
			(start 0.12065 0.3048)
			(end 0.67945 0.3048)
			(stroke
				(width 0.1)
				(type default)
			)
			(layer "B.Fab")
		)
		(fp_line
			(start 0.12065 0.2794)
			(end 0.12065 0.3048)
			(stroke
				(width 0.1)
				(type default)
			)
			(layer "B.Fab")
		)
		(fp_line
			(start 0.12065 -0.2794)
			(end -0.12065 -0.2794)
			(stroke
				(width 0.1)
				(type default)
			)
			(layer "B.Fab")
		)
		(fp_line
			(start 0.12065 -0.305054)
			(end 0.12065 -0.2794)
			(stroke
				(width 0.1)
				(type default)
			)
			(layer "B.Fab")
		)
		(fp_line
			(start -0.120396 0.3048)
			(end -0.120396 0.2794)
			(stroke
				(width 0.1)
				(type default)
			)
			(layer "B.Fab")
		)
		(fp_line
			(start -0.120396 0.2794)
			(end 0.12065 0.2794)
			(stroke
				(width 0.1)
				(type default)
			)
			(layer "B.Fab")
		)
		(fp_line
			(start -0.12065 -0.2794)
			(end -0.12065 -0.3048)
			(stroke
				(width 0.1)
				(type default)
			)
			(layer "B.Fab")
		)
		(fp_line
			(start -0.12065 -0.3048)
			(end -0.67945 -0.3048)
			(stroke
				(width 0.1)
				(type default)
			)
			(layer "B.Fab")
		)
		(fp_line
			(start -0.67945 0.3048)
			(end -0.120396 0.3048)
			(stroke
				(width 0.1)
				(type default)
			)
			(layer "B.Fab")
		)
		(fp_line
			(start -0.67945 -0.3048)
			(end -0.67945 0.3048)
			(stroke
				(width 0.1)
				(type default)
			)
			(layer "B.Fab")
		)
		(pad "1" smd circle
			(at 0.40005 0)
			(size 0 0)
			(layers "B.Cu" "B.Mask" "B.Paste")
			(net "PRSNT_CPU1_N")
		)
		(pad "2" smd circle
			(at -0.40005 0)
			(size 0 0)
			(layers "B.Cu" "B.Mask" "B.Paste")
			(net "FM_PRSNT_CPU1_N")
		)
	)
)
